FILE_TYPE = CONNECTIVITY;
{Allegro Design Entry HDL 17.2-2016 S081 (4005846) 1/11/2022}
"PAGE_NUMBER" = 14;
0"NC";
1"PVNN_TERM_CPU0\g";
2"SVID_ALERT1_CPU0_R_N"CDS_PHYS_NET_NAME"SVID_DIO0_CPU0_R";
3"SVID_DIO1_CPU0_R"CDS_PHYS_NET_NAME"SVID_DIO0_CPU0_R";
4"SVID_ALERT0_CPU0_R_N"$PHYS_NET_NAME"SVID_ALERT0_CPU0_R_N"CDS_PHYS_NET_NAME"SVID_ALERT0_CPU0_R_N";
5"SVID_DIO0_CPU0_R";
6"SVID_DIO0_CPU0_R"CDS_PHYS_NET_NAME"SVID_DIO0_CPU0_R";
7"SMB_PEHPCPU0_GTL_SCL";
8"SMB_PEHPCPU0_GTL_SDA";
9"FM_PEHPCPU0_ALERT_N";
10"PWRGD_DRAMPWRGD_CPU0_AB_LVC1_R";
11"PWRGD_DRAMPWRGD_CPU0_CD_LVC1_R";
12"PWRGD_DRAMPWRGD_CPU0_EF_LVC1_R";
13"PWRGD_DRAMPWRGD_CPU0_GH_LVC1_R";
14"PD_CPU0_ENH_MCECC_DIS";
15"PD_PIROM_CPU0_ADDR2";
16"PD_PIROM_CPU0_ADDR1";
17"PD_PIROM_CPU0_ADDR0";
18"SMB_S3M_CPU0_PIROM_3V3AUX_SCL_R1";
19"SMB_S3M_CPU0_PIROM_3V3AUX_SDA_R1";
20"PU_PIROM_CPU0_SM_WP";
21"TP_H_SBLINK7_CPU0_PMDOWN";
22"TP_H_SBLINK6_CPU0_PMDOWN";
23"TP_H_SBLINK5_CPU0_PMDOWN";
24"TP_H_SBLINK4_CPU0_PMDOWN";
25"TP_H_SBLINK3_CPU0_PMDOWN";
26"TP_H_SBLINK2_CPU0_PMDOWN";
27"H_CPU0_PMDOWN_CPU1_R";
28"H_CPU0_PMDOWN_PCH_R2";
29"TP_H_SBLINK7_CPU0_PMSYNC";
30"TP_H_SBLINK6_CPU0_PMSYNC";
31"TP_H_SBLINK5_CPU0_PMSYNC";
32"TP_H_SBLINK4_CPU0_PMSYNC";
33"TP_H_SBLINK3_CPU0_PMSYNC";
34"TP_H_SBLINK2_CPU0_PMSYNC";
35"H_CPU0_PMSYNC_CPU1_R";
36"H_CPU0_PMSYNC_PCH";
37"PWRGD_CPU0_LVC1";
38"RST_CPU0_LVC1_N";
39"TP_IBL_PLT_RST_SYNC_N";
40"FM_CPU0_SKTOCC_LVT3_N";
41"PU_TAP_ODT_CPU0_EN";
42"H_CPU0_THERMTRIP_LVC1_R_N";
43"TP_EV_CPU0_EXT_BGREF";
44"SVID_DIO1_CPU0";
45"SVID_DIO0_CPU0";
46"SVID_CLK1_CPU0";
47"SVID_CLK0_CPU0";
48"SVID_ALERT1_CPU0_N";
49"SVID_ALERT0_CPU0_N";
50"NC_CPU0_VIEWPIN_DIE11<0>";
51"NC_CPU0_VIEWPIN_DIE01<0>";
52"NC_CPU0_VIEWPIN_DIE01<1>";
53"NC_CPU0_VIEWPIN_DIE00<2>";
54"NC_CPU0_VIEWPIN_DIE01<3>";
55"NC_CPU0_VIEWPIN_DIE00<1>";
56"NC_CPU0_VIEWPIN_DIE01<2>";
57"NC_CPU0_VIEWPIN_DIE00<0>";
58"NC_CPU0_VIEWPIN_DIE00<3>";
59"NC_CPU0_RSVD<144>";
60"NC_CPU0_VIEWPIN_DIE10<1>";
61"NC_CPU0_VIEWPIN_DIE10<3>";
62"NC_CPU0_VIEWPIN_DIE10<2>";
63"NC_CPU0_VIEWPIN_DIE10<0>";
64"NC_CPU0_VIEWPIN_DIE11<1>";
65"NC_CPU0_VIEWPIN_DIE11<2>";
66"NC_CPU0_VIEWPIN_DIE11<3>";
67"H_CPU0_PROCHOT_LVC1_N";
68"H_CPU0_PM_FAST_WAKE_N";
69"H_CPU0_NMI_LVC1_N";
70"H_CPU0_MEMTRIP_LVC1_R_N";
71"H_CPU0_MEMHOT_OUT_LVC1_R_N";
72"H_CPU0_MEMHOT_IN_LVC1_N";
73"FM_CPU_FBRK_DEBUG_R_N";
74"H_CPU0_ERR0_LVC1_R_N";
75"H_CPU0_ERR1_LVC1_R_N";
76"H_CPU0_ERR2_LVC1_R_N";
77"H_CPU0_CATERR_LVC1_R_N";
78"H_CPU0_PMSYNC_CPU1_R";
79"H_CPU0_PMSYNC_CPU1_R1";
80"H_CPU0_PMSYNC_PCH";
81"H_CPU0_PMDOWN_CPU1_R1";
82"H_CPU0_PMDOWN_CPU1_R1";
83"H_CPU0_PMDOWN_CPU1";
84"H_CPU0_PMSYNC_CPU1_R1";
85"H_CPU0_PMDOWN_PCH_R2";
86"SVID_CLK0_CPU0_R";
87"SVID_DIO1_CPU0_R";
88"SVID_CLK1_CPU0_R";
89"SVID_ALERT0_CPU0_R_N";
90"SVID_ALERT1_CPU0_R_N";
91"H_CPU0_PMDOWN_PCH_R";
92"H_CPU0_PMSYNC_PCH_R2";
93"H_CPU0_PMSYNC_PCH_R";
94"SMB_S3M_CPU0_PIROM_3V3AUX_SDA";
95"SMB_S3M_CPU0_PIROM_3V3AUX_SCL";
96"H_CPU0_PMDOWN_PCH_R";
97"H_CPU0_PMSYNC_PCH_R";
98"H_CPU0_PMDOWN_PCH";
99"H_CPU0_PMDOWN_CPU1_R";
100"H_CPU0_PMSYNC_CPU1";
%"SOCKET4677_AZIF0045P001C01CS"
"2","(-350,3250)","0","pure_quanta","I1";
;
PART_NUMBER"DGA^7000023"
VALUE"SOCKET4677_AZIF0045-P001C01CS"
MATERIAL"IO"
PART_TYPE"SMLF"
$LOCATION"U2"
CDS_LMAN_SYM_OUTLINE"-1100,1400,1050,-1400"
NEEDS_NO_SIZE"TRUE"
CDS_LIB"pure_quanta"
CDS_LOCATION"U2"
$SEC"2"
CDS_SEC"2";
"THERMTRIP_N \B"
$PN"BL62"42;
"RSVD19"
$PN"AV59"43;
"TAP_ODT_EN"
$PN"AY20"41;
"SVIDDATA1"
$PN"BL25"44;
"SVIDDATA0"
$PN"BD26"45;
"SVIDCLK1"
$PN"BF26"46;
"SVIDCLK0"
$PN"BH26"47;
"SVIDALERT1_N \B"
$PN"BJ25"48;
"SVIDALERT0_N \B"
$PN"BK26"49;
"SKTOCC_N \B"
$PN"CG66"40;
"RSVD104"
$PN"CJ62"50;
"RSVD70"
$PN"BP69"51;
"RSVD69"
$PN"BP67"52;
"RSVD6"
$PN"AU25"53;
"RSVD59"
$PN"BJ70"54;
"RSVD4"
$PN"AT24"55;
"RSVD29"
$PN"AY65"56;
"RSVD27"
$PN"AY26"57;
"RSVD15"
$PN"AV26"58;
"RSVD150"
$PN"CW68"59;
"RSVD146"
$PN"CW25"60;
"RSVD145"
$PN"CW23"61;
"RSVD141"
$PN"CV24"62;
"RSVD132"
$PN"CR23"63;
"RSVD126"
$PN"CN62"64;
"RSVD121"
$PN"CM63"65;
"RSVD116"
$PN"CL64"66;
"RSVD113"
$PN"CL21"39;
"RESET_N \B"
$PN"BH61"38;
"PWRGOOD"
$PN"AV20"37;
"PROCHOT_N \B"
$PN"AU19"67;
"PMSYNC_PCH"
$PN"DA39"36;
"PMSYNC0"
$PN"CN25"35;
"PMSYNC1"
$PN"CL25"34;
"PMSYNC2"
$PN"CH26"33;
"PMSYNC3"
$PN"CE25"32;
"PMSYNC4"
$PN"CR19"31;
"PMSYNC5"
$PN"CH24"30;
"PMSYNC6"
$PN"CF24"29;
"PMFAST_WAKE_N \B"
$PN"CP20"68;
"PMDOWN_PCH"
$PN"CY40"28;
"PMDOWN0"
$PN"CW39"27;
"PMDOWN1"
$PN"CP26"26;
"PMDOWN2"
$PN"CM26"25;
"PMDOWN3"
$PN"CD24"24;
"PMDOWN4"
$PN"CV18"23;
"PMDOWN5"
$PN"CE23"22;
"PMDOWN6"
$PN"CC25"21;
"PIROM_SM_WP"
$PN"CR72"20;
"PIROM_SDA"
$PN"CM71"19;
"PIROM_SCL"
$PN"CU70"18;
"PIROM_AD0"
$PN"CR70"17;
"PIROM_AD1"
$PN"CT71"16;
"PIROM_AD2"
$PN"CP71"15;
"NMI"
$PN"AV18"69;
"MEMTRIP_N \B"
$PN"AV24"70;
"MEMHOT_OUT_N \B"
$PN"CF26"71;
"MEMHOT_IN_N \B"
$PN"AU21"72;
"FBRK_N \B"
$PN"AV57"73;
"ERROR_N0 \B"
$PN"BF22"74;
"ERROR_N1 \B"
$PN"AY22"75;
"ERROR_N2 \B"
$PN"BD22"76;
"RSVD96"
$PN"CH22"14;
"DDR67_DRAM_PWR_OK"
$PN"CW45"13;
"DDR45_DRAM_PWR_OK"
$PN"CY44"12;
"DDR23_DRAM_PWR_OK"
$PN"F47"11;
"DDR01_DRAM_PWR_OK"
$PN"A43"10;
"CXPSMBUS_ALERT_N \B"
$PN"BV26"9;
"CXPSMBUSSDA"
$PN"BY26"8;
"CXPSMBUSSCL"
$PN"CA25"7;
"CATERR_N \B"
$PN"BP24"77;
%"Q_RES"
"1","(2975,-225)","0","pure_quanta","I100";
;
PART_NUMBER"CS04992FB07"
TOLERANCE"1%"
VALUE"49.9"
MATERIAL"CHIP"
WATTAGE"1/16W"
PACK_TYPE"0402LF"
$LOCATION"R556"
CDS_LIB"pure_quanta"
CDS_LOCATION"R556"
$SEC"1"
CDS_SEC"1";
"B"
$PN"2"1;
"A"
$PN"1"2;
%"Q_RES"
"1","(-3075,4300)","0","pure_quanta","I109";
;
PART_NUMBER"CS03322FB03"
PACK_TYPE"0402LF"
WATTAGE"1/16W"
MATERIAL"CHIP"
VALUE"33.2"
TOLERANCE"1%"
$LOCATION"R1932"
CDS_LIB"pure_quanta"
CDS_LOCATION"R1932"
$SEC"1"
CDS_SEC"1";
"B"
$PN"2"18;
"A"
$PN"1"95;
%"Q_RES"
"1","(-3075,4250)","0","pure_quanta","I110";
;
PART_NUMBER"CS03322FB03"
MATERIAL"CHIP"
TOLERANCE"1%"
VALUE"33.2"
$LOCATION"R1933"
WATTAGE"1/16W"
PACK_TYPE"0402LF"
CDS_LIB"pure_quanta"
CDS_LOCATION"R1933"
$SEC"1"
CDS_SEC"1";
"B"
$PN"2"19;
"A"
$PN"1"94;
%"Q_RES"
"1","(-1600,1425)","0","pure_quanta","I115";
;
PART_NUMBER"CS00002JB13"
WATTAGE"1/16W"
PACK_TYPE"0402LF"
VALUE"0"
MATERIAL"CHIP"
TOLERANCE"5%"
$LOCATION"R1959"
CDS_LIB"pure_quanta"
CDS_LOCATION"R1959"
$SEC"1"
CDS_SEC"1";
"B"
$PN"2"96;
"A"
$PN"1"85;
%"Q_RES"
"1","(-1600,750)","0","pure_quanta","I117";
;
PART_NUMBER"CS00002JB13"
TOLERANCE"5%"
MATERIAL"CHIP"
PACK_TYPE"0402LF"
WATTAGE"1/16W"
VALUE"0"
$LOCATION"R1960"
CDS_LIB"pure_quanta"
CDS_LOCATION"R1960"
$SEC"1"
CDS_SEC"1";
"B"
$PN"2"97;
"A"
$PN"1"92;
%"Q_RES"
"1","(-1600,25)","0","pure_quanta","I122";
;
PART_NUMBER"CS03322FB03"
VALUE"33.2"
TOLERANCE"1%"
WATTAGE"1/16W"
MATERIAL"CHIP"
PACK_TYPE"0402LF"
$LOCATION"R2362"
CDS_LIB"pure_quanta"
CDS_LOCATION"R2362"
$SEC"1"
CDS_SEC"1";
"B"
$PN"2"82;
"A"
$PN"1"99;
%"Q_RES"
"1","(-1600,-725)","0","pure_quanta","I128";
;
PART_NUMBER"CS03322FB03"
MATERIAL"CHIP"
TOLERANCE"1%"
WATTAGE"1/16W"
VALUE"33.2"
PACK_TYPE"0402LF"
$LOCATION"R4089"
CDS_LIB"pure_quanta"
CDS_LOCATION"R4089"
$SEC"1"
CDS_SEC"1";
"B"
$PN"2"100;
"A"
$PN"1"79;
%"Q_RES"
"1","(2000,4500)","0","pure_quanta","I59";
;
PART_NUMBER"CS00002JB13"
WATTAGE"1/16W"
MATERIAL"CHIP"
VALUE"0"
TOLERANCE"5%"
PACK_TYPE"0402LF"
$LOCATION"R12"
CDS_LIB"pure_quanta"
$LOCATION"R12"
CDS_LOCATION"R12"
$SEC"1"
CDS_SEC"1";
"B"
$PN"2"5;
"A"
$PN"1"45;
%"Q_RES"
"1","(2000,4450)","0","pure_quanta","I60";
;
PART_NUMBER"CS00002JB13"
VALUE"0"
TOLERANCE"5%"
PACK_TYPE"0402LF"
$LOCATION"R13"
CDS_LIB"pure_quanta"
WATTAGE"1/16W"
MATERIAL"CHIP"
$LOCATION"R13"
CDS_LOCATION"R13"
$SEC"1"
CDS_SEC"1";
"B"
$PN"2"86;
"A"
$PN"1"47;
%"Q_RES"
"1","(2000,4400)","0","pure_quanta","I61";
;
PART_NUMBER"CS12002FB06"
MATERIAL"CHIP"
TOLERANCE"1%"
VALUE"200"
WATTAGE"1/16W"
PACK_TYPE"0402LF"
$LOCATION"R14"
CDS_LIB"pure_quanta"
CDS_LOCATION"R14"
$SEC"1"
CDS_SEC"1";
"B"
$PN"2"89;
"A"
$PN"1"49;
%"Q_RES"
"1","(2000,4300)","0","pure_quanta","I62";
;
PART_NUMBER"CS00002JB13"
TOLERANCE"5%"
VALUE"0"
PACK_TYPE"0402LF"
$LOCATION"R15"
CDS_LIB"pure_quanta"
WATTAGE"1/16W"
MATERIAL"CHIP"
$LOCATION"R15"
CDS_LOCATION"R15"
$SEC"1"
CDS_SEC"1";
"B"
$PN"2"87;
"A"
$PN"1"44;
%"Q_RES"
"1","(2000,4250)","0","pure_quanta","I63";
;
PART_NUMBER"CS00002JB13"
TOLERANCE"5%"
PACK_TYPE"0402LF"
VALUE"0"
$LOCATION"R16"
CDS_LIB"pure_quanta"
MATERIAL"CHIP"
WATTAGE"1/16W"
$LOCATION"R16"
CDS_LOCATION"R16"
$SEC"1"
CDS_SEC"1";
"B"
$PN"2"88;
"A"
$PN"1"46;
%"Q_RES"
"1","(2000,4200)","0","pure_quanta","I64";
;
PART_NUMBER"CS12002FB06"
MATERIAL"CHIP"
WATTAGE"1/16W"
PACK_TYPE"0402LF"
TOLERANCE"1%"
VALUE"200"
$LOCATION"R17"
CDS_LIB"pure_quanta"
CDS_LOCATION"R17"
$SEC"1"
CDS_SEC"1";
"B"
$PN"2"90;
"A"
$PN"1"48;
%"Q_RES"
"1","(-1600,1200)","0","pure_quanta","I66";
;
PART_NUMBER"CS03322FB03"
VALUE"33.2"
WATTAGE"1/16W"
TOLERANCE"1%"
MATERIAL"CHIP"
PACK_TYPE"0402LF"
$LOCATION"R7"
CDS_LIB"pure_quanta"
$LOCATION"R7"
CDS_LOCATION"R7"
$SEC"1"
CDS_SEC"1";
"B"
$PN"2"98;
"A"
$PN"1"91;
%"Q_RES"
"1","(-1600,500)","0","pure_quanta","I78";
;
PART_NUMBER"CS03322FB03"
TOLERANCE"1%"
MATERIAL"CHIP"
PACK_TYPE"0402LF"
WATTAGE"1/16W"
VALUE"33.2"
$LOCATION"R10"
CDS_LIB"pure_quanta"
$LOCATION"R10"
CDS_LOCATION"R10"
$SEC"1"
CDS_SEC"1";
"B"
$PN"2"80;
"A"
$PN"1"93;
%"Q_RES"
"1","(-1600,-225)","0","pure_quanta","I79";
;
PART_NUMBER"CS03322FB03"
WATTAGE"1/16W"
VALUE"33.2"
TOLERANCE"1%"
MATERIAL"CHIP"
PACK_TYPE"0402LF"
$LOCATION"R11"
CDS_LIB"pure_quanta"
$LOCATION"R11"
CDS_LOCATION"R11"
$SEC"1"
CDS_SEC"1";
"B"
$PN"2"83;
"A"
$PN"1"81;
%"Q_RES"
"1","(-1600,-475)","0","pure_quanta","I90";
;
PART_NUMBER"CS03322FB03"
WATTAGE"1/16W"
VALUE"33.2"
TOLERANCE"1%"
MATERIAL"CHIP"
PACK_TYPE"0402LF"
$LOCATION"R322"
CDS_LIB"pure_quanta"
CDS_LOCATION"R322"
$SEC"1"
CDS_SEC"1";
"B"
$PN"2"84;
"A"
$PN"1"78;
%"Q_RES"
"1","(2975,375)","0","pure_quanta","I93";
;
PART_NUMBER"CS11002FB07"
PACK_TYPE"0402LF"
VALUE"100"
TOLERANCE"1%"
WATTAGE"1/16W"
MATERIAL"CHIP"
$LOCATION"R328"
CDS_LIB"pure_quanta"
CDS_LOCATION"R328"
$SEC"1"
CDS_SEC"1";
"B"
$PN"2"1;
"A"
$PN"1"6;
%"Q_RES"
"1","(2975,175)","0","pure_quanta","I94";
;
PART_NUMBER"CS04992FB07"
TOLERANCE"1%"
MATERIAL"CHIP"
PACK_TYPE"0402LF"
WATTAGE"1/16W"
VALUE"49.9"
$LOCATION"R548"
CDS_LIB"pure_quanta"
CDS_LOCATION"R548"
$SEC"1"
CDS_SEC"1";
"B"
$PN"2"1;
"A"
$PN"1"4;
%"UNIVERSAL_POWER"
"1","(3525,600)","0","logical_power","I95";
;
HDL_POWER"PVNN_TERM_CPU0"
CDS_LIB"logical_power";
"A"1;
%"Q_RES"
"1","(2975,-25)","0","pure_quanta","I98";
;
PART_NUMBER"CS11002FB07"
MATERIAL"CHIP"
VALUE"100"
PACK_TYPE"0402LF"
TOLERANCE"1%"
WATTAGE"1/16W"
$LOCATION"R555"
CDS_LIB"pure_quanta"
CDS_LOCATION"R555"
$SEC"1"
CDS_SEC"1";
"B"
$PN"2"1;
"A"
$PN"1"3;
END.
